(kicad_pcb
	(version 20260206)
	(generator "pcbnew")
	(generator_version "10.0")
	(general
		(thickness 1.6)
		(legacy_teardrops no)
	)
	(paper "A4")
	(title_block
		(title "03242023_DA0F0TMBIJ0_F0T_Motherboard_J_brd_V01_OCP.brd")
		(comment 1 "Grand Teton / footprint 2194 of 6105 (J15), pads 225-291 of 291")
	)
	(layers
		(0 "F.Cu" signal "TOP")
		(4 "In1.Cu" signal "GND")
		(6 "In2.Cu" signal "IN1")
		(8 "In3.Cu" signal "GND1")
		(10 "In4.Cu" signal "IN2")
		(12 "In5.Cu" signal "GND2")
		(14 "In6.Cu" signal "IN3")
		(16 "In7.Cu" signal "GND3")
		(18 "In8.Cu" signal "VCC")
		(20 "In9.Cu" signal "VCC1")
		(22 "In10.Cu" signal "GND4")
		(24 "In11.Cu" signal "IN4")
		(26 "In12.Cu" signal "GND5")
		(28 "In13.Cu" signal "IN5")
		(30 "In14.Cu" signal "GND6")
		(32 "In15.Cu" signal "IN6")
		(34 "In16.Cu" signal "GND7")
		(2 "B.Cu" signal "BOTTOM")
		(9 "F.Adhes" user "F.Adhesive")
		(11 "B.Adhes" user "B.Adhesive")
		(13 "F.Paste" user "Package Geometry/Pastemask Top")
		(15 "B.Paste" user "Package Geometry/Pastemask Bottom")
		(5 "F.SilkS" user "Ref Des/Silkscreen Top")
		(7 "B.SilkS" user "Ref Des/Silkscreen Bottom")
		(1 "F.Mask" user "Board Geometry/Soldermask Top")
		(3 "B.Mask" user "Board Geometry/Soldermask Bottom")
		(17 "Dwgs.User" user "User.Drawings")
		(19 "Cmts.User" user "User.Comments")
		(21 "Eco1.User" user "User.Eco1")
		(23 "Eco2.User" user "User.Eco2")
		(25 "Edge.Cuts" user "Board Geometry/Outline")
		(27 "Margin" user)
		(31 "F.CrtYd" user "Package Geometry/Place Bound Top")
		(29 "B.CrtYd" user "Package Geometry/Place Bound Bottom")
		(35 "F.Fab" user "Ref Des/Assembly Top")
		(33 "B.Fab" user "Ref Des/Assembly Bottom")
	)
	(footprint ""
		(layer "F.Cu")
		(at 461.609948 -258.091686)
		(property "Reference" "J15"
			(at 3.019552 -81.652872 0)
			(unlocked yes)
			(layer "F.SilkS")
			(effects
				(font
					(size 0.7874 0.5842)
					(thickness 0.1524)
				)
				(justify left)
			)
		)
		(property "Value" ""
			(at 0 0 0)
			(layer "F.Fab")
			(effects
				(font
					(size 1.27 1.27)
				)
			)
		)
		(duplicate_pad_numbers_are_jumpers no)
		(pad "225" smd rect
			(at 2.050034 9.774936 270)
			(size 0.519938 1.4986)
			(layers "F.Cu" "F.Mask" "F.Paste")
			(net "M_H_CPU0_SB_CA<5>")
		)
		(pad "226" smd rect
			(at 2.050034 10.625074 270)
			(size 0.519938 1.4986)
			(layers "F.Cu" "F.Mask" "F.Paste")
			(net "GND")
		)
		(pad "227" smd rect
			(at 2.050034 11.474958 270)
			(size 0.519938 1.4986)
			(layers "F.Cu" "F.Mask" "F.Paste")
			(net "M_H_CPU0_SB_PAR")
		)
		(pad "228" smd rect
			(at 2.050034 12.325096 270)
			(size 0.519938 1.4986)
			(layers "F.Cu" "F.Mask" "F.Paste")
			(net "GND")
		)
		(pad "229" smd rect
			(at 2.050034 13.17498 270)
			(size 0.519938 1.4986)
			(layers "F.Cu" "F.Mask" "F.Paste")
			(net "M_H_CPU0_SB_CS_N<1>")
		)
		(pad "230" smd rect
			(at 2.050034 14.025118 270)
			(size 0.519938 1.4986)
			(layers "F.Cu" "F.Mask" "F.Paste")
			(net "GND")
		)
		(pad "231" smd rect
			(at 2.050034 14.875002 270)
			(size 0.519938 1.4986)
			(layers "F.Cu" "F.Mask" "F.Paste")
			(net "TP_CHH_CPU0_DIMM1_FRU_5")
		)
		(pad "232" smd rect
			(at 2.050034 15.724886 270)
			(size 0.519938 1.4986)
			(layers "F.Cu" "F.Mask" "F.Paste")
			(net "TP_CHH_CPU0_DIMM1_FRU_6")
		)
		(pad "233" smd rect
			(at 2.050034 16.575024 270)
			(size 0.519938 1.4986)
			(layers "F.Cu" "F.Mask" "F.Paste")
			(net "GND")
		)
		(pad "234" smd rect
			(at 2.050034 17.424908 270)
			(size 0.519938 1.4986)
			(layers "F.Cu" "F.Mask" "F.Paste")
			(net "M_H_CPU0_SB_CB<6>")
		)
		(pad "235" smd rect
			(at 2.050034 18.275046 270)
			(size 0.519938 1.4986)
			(layers "F.Cu" "F.Mask" "F.Paste")
			(net "GND")
		)
		(pad "236" smd rect
			(at 2.050034 19.12493 270)
			(size 0.519938 1.4986)
			(layers "F.Cu" "F.Mask" "F.Paste")
			(net "M_H_CPU0_SB_CB<7>")
		)
		(pad "237" smd rect
			(at 2.050034 19.975068 270)
			(size 0.519938 1.4986)
			(layers "F.Cu" "F.Mask" "F.Paste")
			(net "GND")
		)
		(pad "238" smd rect
			(at 2.050034 20.824952 270)
			(size 0.519938 1.4986)
			(layers "F.Cu" "F.Mask" "F.Paste")
			(net "M_H_CPU0_SB_DQS_DN<4>")
		)
		(pad "239" smd rect
			(at 2.050034 21.67509 270)
			(size 0.519938 1.4986)
			(layers "F.Cu" "F.Mask" "F.Paste")
			(net "M_H_CPU0_SB_DQS_DP<4>")
		)
		(pad "240" smd rect
			(at 2.050034 22.524974 270)
			(size 0.519938 1.4986)
			(layers "F.Cu" "F.Mask" "F.Paste")
			(net "GND")
		)
		(pad "241" smd rect
			(at 2.050034 23.375112 270)
			(size 0.519938 1.4986)
			(layers "F.Cu" "F.Mask" "F.Paste")
			(net "M_H_CPU0_SB_CB<2>")
		)
		(pad "242" smd rect
			(at 2.050034 24.224996 270)
			(size 0.519938 1.4986)
			(layers "F.Cu" "F.Mask" "F.Paste")
			(net "GND")
		)
		(pad "243" smd rect
			(at 2.050034 25.07488 270)
			(size 0.519938 1.4986)
			(layers "F.Cu" "F.Mask" "F.Paste")
			(net "M_H_CPU0_SB_CB<3>")
		)
		(pad "244" smd rect
			(at 2.050034 25.925018 270)
			(size 0.519938 1.4986)
			(layers "F.Cu" "F.Mask" "F.Paste")
			(net "GND")
		)
		(pad "245" smd rect
			(at 2.050034 26.774902 270)
			(size 0.519938 1.4986)
			(layers "F.Cu" "F.Mask" "F.Paste")
			(net "M_H_CPU0_SB_DQ<2>")
		)
		(pad "246" smd rect
			(at 2.050034 27.62504 270)
			(size 0.519938 1.4986)
			(layers "F.Cu" "F.Mask" "F.Paste")
			(net "GND")
		)
		(pad "247" smd rect
			(at 2.050034 28.474924 270)
			(size 0.519938 1.4986)
			(layers "F.Cu" "F.Mask" "F.Paste")
			(net "M_H_CPU0_SB_DQ<3>")
		)
		(pad "248" smd rect
			(at 2.050034 29.325062 270)
			(size 0.519938 1.4986)
			(layers "F.Cu" "F.Mask" "F.Paste")
			(net "GND")
		)
		(pad "249" smd rect
			(at 2.050034 30.174946 270)
			(size 0.519938 1.4986)
			(layers "F.Cu" "F.Mask" "F.Paste")
			(net "M_H_CPU0_SB_DQS_DN<5>")
		)
		(pad "250" smd rect
			(at 2.050034 31.025084 270)
			(size 0.519938 1.4986)
			(layers "F.Cu" "F.Mask" "F.Paste")
			(net "M_H_CPU0_SB_DQS_DP<5>")
		)
		(pad "251" smd rect
			(at 2.050034 31.874968 270)
			(size 0.519938 1.4986)
			(layers "F.Cu" "F.Mask" "F.Paste")
			(net "GND")
		)
		(pad "252" smd rect
			(at 2.050034 32.725106 270)
			(size 0.519938 1.4986)
			(layers "F.Cu" "F.Mask" "F.Paste")
			(net "M_H_CPU0_SB_DQ<6>")
		)
		(pad "253" smd rect
			(at 2.050034 33.57499 270)
			(size 0.519938 1.4986)
			(layers "F.Cu" "F.Mask" "F.Paste")
			(net "GND")
		)
		(pad "254" smd rect
			(at 2.050034 34.425128 270)
			(size 0.519938 1.4986)
			(layers "F.Cu" "F.Mask" "F.Paste")
			(net "M_H_CPU0_SB_DQ<7>")
		)
		(pad "255" smd rect
			(at 2.050034 35.275012 270)
			(size 0.519938 1.4986)
			(layers "F.Cu" "F.Mask" "F.Paste")
			(net "GND")
		)
		(pad "256" smd rect
			(at 2.050034 36.124896 270)
			(size 0.519938 1.4986)
			(layers "F.Cu" "F.Mask" "F.Paste")
			(net "M_H_CPU0_SB_DQ<10>")
		)
		(pad "257" smd rect
			(at 2.050034 36.975034 270)
			(size 0.519938 1.4986)
			(layers "F.Cu" "F.Mask" "F.Paste")
			(net "GND")
		)
		(pad "258" smd rect
			(at 2.050034 37.824918 270)
			(size 0.519938 1.4986)
			(layers "F.Cu" "F.Mask" "F.Paste")
			(net "M_H_CPU0_SB_DQ<11>")
		)
		(pad "259" smd rect
			(at 2.050034 38.675056 270)
			(size 0.519938 1.4986)
			(layers "F.Cu" "F.Mask" "F.Paste")
			(net "GND")
		)
		(pad "260" smd rect
			(at 2.050034 39.52494 270)
			(size 0.519938 1.4986)
			(layers "F.Cu" "F.Mask" "F.Paste")
			(net "M_H_CPU0_SB_DQS_DN<6>")
		)
		(pad "261" smd rect
			(at 2.050034 40.375078 270)
			(size 0.519938 1.4986)
			(layers "F.Cu" "F.Mask" "F.Paste")
			(net "M_H_CPU0_SB_DQS_DP<6>")
		)
		(pad "262" smd rect
			(at 2.050034 41.224962 270)
			(size 0.519938 1.4986)
			(layers "F.Cu" "F.Mask" "F.Paste")
			(net "GND")
		)
		(pad "263" smd rect
			(at 2.050034 42.0751 270)
			(size 0.519938 1.4986)
			(layers "F.Cu" "F.Mask" "F.Paste")
			(net "M_H_CPU0_SB_DQ<14>")
		)
		(pad "264" smd rect
			(at 2.050034 42.924984 270)
			(size 0.519938 1.4986)
			(layers "F.Cu" "F.Mask" "F.Paste")
			(net "GND")
		)
		(pad "265" smd rect
			(at 2.050034 43.775122 270)
			(size 0.519938 1.4986)
			(layers "F.Cu" "F.Mask" "F.Paste")
			(net "M_H_CPU0_SB_DQ<15>")
		)
		(pad "266" smd rect
			(at 2.050034 44.625006 270)
			(size 0.519938 1.4986)
			(layers "F.Cu" "F.Mask" "F.Paste")
			(net "GND")
		)
		(pad "267" smd rect
			(at 2.050034 45.47489 270)
			(size 0.519938 1.4986)
			(layers "F.Cu" "F.Mask" "F.Paste")
			(net "M_H_CPU0_SB_DQ<18>")
		)
		(pad "268" smd rect
			(at 2.050034 46.325028 270)
			(size 0.519938 1.4986)
			(layers "F.Cu" "F.Mask" "F.Paste")
			(net "GND")
		)
		(pad "269" smd rect
			(at 2.050034 47.174912 270)
			(size 0.519938 1.4986)
			(layers "F.Cu" "F.Mask" "F.Paste")
			(net "M_H_CPU0_SB_DQ<19>")
		)
		(pad "270" smd rect
			(at 2.050034 48.02505 270)
			(size 0.519938 1.4986)
			(layers "F.Cu" "F.Mask" "F.Paste")
			(net "GND")
		)
		(pad "271" smd rect
			(at 2.050034 48.874934 270)
			(size 0.519938 1.4986)
			(layers "F.Cu" "F.Mask" "F.Paste")
			(net "M_H_CPU0_SB_DQS_DN<7>")
		)
		(pad "272" smd rect
			(at 2.050034 49.725072 270)
			(size 0.519938 1.4986)
			(layers "F.Cu" "F.Mask" "F.Paste")
			(net "M_H_CPU0_SB_DQS_DP<7>")
		)
		(pad "273" smd rect
			(at 2.050034 50.574956 270)
			(size 0.519938 1.4986)
			(layers "F.Cu" "F.Mask" "F.Paste")
			(net "GND")
		)
		(pad "274" smd rect
			(at 2.050034 51.425094 270)
			(size 0.519938 1.4986)
			(layers "F.Cu" "F.Mask" "F.Paste")
			(net "M_H_CPU0_SB_DQ<22>")
		)
		(pad "275" smd rect
			(at 2.050034 52.274978 270)
			(size 0.519938 1.4986)
			(layers "F.Cu" "F.Mask" "F.Paste")
			(net "GND")
		)
		(pad "276" smd rect
			(at 2.050034 53.125116 270)
			(size 0.519938 1.4986)
			(layers "F.Cu" "F.Mask" "F.Paste")
			(net "M_H_CPU0_SB_DQ<23>")
		)
		(pad "277" smd rect
			(at 2.050034 53.975 270)
			(size 0.519938 1.4986)
			(layers "F.Cu" "F.Mask" "F.Paste")
			(net "GND")
		)
		(pad "278" smd rect
			(at 2.050034 54.824884 270)
			(size 0.519938 1.4986)
			(layers "F.Cu" "F.Mask" "F.Paste")
			(net "M_H_CPU0_SB_DQ<26>")
		)
		(pad "279" smd rect
			(at 2.050034 55.675022 270)
			(size 0.519938 1.4986)
			(layers "F.Cu" "F.Mask" "F.Paste")
			(net "GND")
		)
		(pad "280" smd rect
			(at 2.050034 56.524906 270)
			(size 0.519938 1.4986)
			(layers "F.Cu" "F.Mask" "F.Paste")
			(net "M_H_CPU0_SB_DQ<27>")
		)
		(pad "281" smd rect
			(at 2.050034 57.375044 270)
			(size 0.519938 1.4986)
			(layers "F.Cu" "F.Mask" "F.Paste")
			(net "GND")
		)
		(pad "282" smd rect
			(at 2.050034 58.224928 270)
			(size 0.519938 1.4986)
			(layers "F.Cu" "F.Mask" "F.Paste")
			(net "M_H_CPU0_SB_DQS_DN<8>")
		)
		(pad "283" smd rect
			(at 2.050034 59.075066 270)
			(size 0.519938 1.4986)
			(layers "F.Cu" "F.Mask" "F.Paste")
			(net "M_H_CPU0_SB_DQS_DP<8>")
		)
		(pad "284" smd rect
			(at 2.050034 59.92495 270)
			(size 0.519938 1.4986)
			(layers "F.Cu" "F.Mask" "F.Paste")
			(net "GND")
		)
		(pad "285" smd rect
			(at 2.050034 60.775088 270)
			(size 0.519938 1.4986)
			(layers "F.Cu" "F.Mask" "F.Paste")
			(net "M_H_CPU0_SB_DQ<30>")
		)
		(pad "286" smd rect
			(at 2.050034 61.624972 270)
			(size 0.519938 1.4986)
			(layers "F.Cu" "F.Mask" "F.Paste")
			(net "GND")
		)
		(pad "287" smd rect
			(at 2.050034 62.47511 270)
			(size 0.519938 1.4986)
			(layers "F.Cu" "F.Mask" "F.Paste")
			(net "M_H_CPU0_SB_DQ<31>")
		)
		(pad "288" smd rect
			(at 2.050034 63.324994 270)
			(size 0.519938 1.4986)
			(layers "F.Cu" "F.Mask" "F.Paste")
			(net "GND")
		)
		(pad "G1" thru_hole oval
			(at 0 -68.97497)
			(size 2.8194 1.5748)
			(drill oval 2.4384 1.1938)
			(layers "*.Cu" "*.Mask")
			(remove_unused_layers no)
			(net "GND")
			(clearance 0.127)
			(thermal_gap 0.127)
		)
		(pad "G2" thru_hole oval
			(at 0 3.875024)
			(size 2.8194 1.5748)
			(drill oval 2.4384 1.1938)
			(layers "*.Cu" "*.Mask")
			(remove_unused_layers no)
			(net "GND")
			(clearance 0.127)
			(thermal_gap 0.127)
		)
		(pad "G3" thru_hole oval
			(at 0 68.97497)
			(size 2.8194 1.5748)
			(drill oval 2.4384 1.1938)
			(layers "*.Cu" "*.Mask")
			(remove_unused_layers no)
			(net "GND")
			(clearance 0.127)
			(thermal_gap 0.127)
		)
	)
)
